# S9S_MB_2U (Grand Teton) — schematic netlist excerpt (pin names and nets, part order shuffled) for the footprints in the layout excerpt that follows; sources: Cadence DE-HDL packaged netlist, KiCad conversion of 03242023_DA0F0TMBIJ0_F0T_Motherboard_J_brd_V01_OCP.brd

D94  Q_LED  IC  pkg SMLF  page 252 : A = LED_FM_PCH_SLP_S4_N ; C = LED_FM_PCH_SLP_S4_N_D
PC394  Q_CAP  1UF 16V 10% X6S  pkg C0402  page 296 : A = PVCCD_HV_CPU1_VCC ; B = GND

(kicad_pcb
	(version 20260206)
	(generator "pcbnew")
	(generator_version "10.0")
	(general
		(thickness 1.6)
		(legacy_teardrops no)
	)
	(paper "A4")
	(title_block
		(title "03242023_DA0F0TMBIJ0_F0T_Motherboard_J_brd_V01_OCP.brd")
		(comment 1 "Grand Teton / footprints 3383-3384 of 6105")
	)
	(layers
		(0 "F.Cu" signal "TOP")
		(4 "In1.Cu" signal "GND")
		(6 "In2.Cu" signal "IN1")
		(8 "In3.Cu" signal "GND1")
		(10 "In4.Cu" signal "IN2")
		(12 "In5.Cu" signal "GND2")
		(14 "In6.Cu" signal "IN3")
		(16 "In7.Cu" signal "GND3")
		(18 "In8.Cu" signal "VCC")
		(20 "In9.Cu" signal "VCC1")
		(22 "In10.Cu" signal "GND4")
		(24 "In11.Cu" signal "IN4")
		(26 "In12.Cu" signal "GND5")
		(28 "In13.Cu" signal "IN5")
		(30 "In14.Cu" signal "GND6")
		(32 "In15.Cu" signal "IN6")
		(34 "In16.Cu" signal "GND7")
		(2 "B.Cu" signal "BOTTOM")
		(9 "F.Adhes" user "F.Adhesive")
		(11 "B.Adhes" user "B.Adhesive")
		(13 "F.Paste" user "Package Geometry/Pastemask Top")
		(15 "B.Paste" user "Package Geometry/Pastemask Bottom")
		(5 "F.SilkS" user "Ref Des/Silkscreen Top")
		(7 "B.SilkS" user "Ref Des/Silkscreen Bottom")
		(1 "F.Mask" user "Board Geometry/Soldermask Top")
		(3 "B.Mask" user "Board Geometry/Soldermask Bottom")
		(17 "Dwgs.User" user "User.Drawings")
		(19 "Cmts.User" user "User.Comments")
		(21 "Eco1.User" user "User.Eco1")
		(23 "Eco2.User" user "User.Eco2")
		(25 "Edge.Cuts" user "Board Geometry/Outline")
		(27 "Margin" user)
		(31 "F.CrtYd" user "Package Geometry/Place Bound Top")
		(29 "B.CrtYd" user "Package Geometry/Place Bound Bottom")
		(35 "F.Fab" user "Ref Des/Assembly Top")
		(33 "B.Fab" user "Ref Des/Assembly Bottom")
	)
	(footprint ""
		(layer "F.Cu")
		(at 99.998276 -79.078836)
		(property "Reference" "D94"
			(at -50.01641 38.649402 90)
			(unlocked yes)
			(layer "F.SilkS")
			(effects
				(font
					(size 0.635 0.4064)
					(thickness 0.1524)
				)
				(justify left)
			)
		)
		(property "Value" ""
			(at 0 0 0)
			(layer "F.Fab")
			(effects
				(font
					(size 1.27 1.27)
				)
			)
		)
		(duplicate_pad_numbers_are_jumpers no)
		(fp_line
			(start -0.90678 0.4826)
			(end -0.90678 -0.4699)
			(stroke
				(width 0.1524)
				(type default)
			)
			(layer "F.SilkS")
		)
		(fp_line
			(start -0.89408 -0.4826)
			(end 0.90678 -0.4826)
			(stroke
				(width 0.1524)
				(type default)
			)
			(layer "F.SilkS")
		)
		(fp_line
			(start -0.79248 -0.4826)
			(end 1.03378 -0.4826)
			(stroke
				(width 0.1524)
				(type default)
			)
			(layer "F.SilkS")
		)
		(fp_line
			(start -0.64008 -0.4826)
			(end 1.16078 -0.4826)
			(stroke
				(width 0.1524)
				(type default)
			)
			(layer "F.SilkS")
		)
		(fp_line
			(start 0.90678 -0.4826)
			(end 0.90678 0.4826)
			(stroke
				(width 0.1524)
				(type default)
			)
			(layer "F.SilkS")
		)
		(fp_line
			(start 0.90678 0.4826)
			(end -0.90678 0.4826)
			(stroke
				(width 0.1524)
				(type default)
			)
			(layer "F.SilkS")
		)
		(fp_line
			(start 1.03378 -0.4826)
			(end 1.03378 0.4826)
			(stroke
				(width 0.1524)
				(type default)
			)
			(layer "F.SilkS")
		)
		(fp_line
			(start 1.03378 0.4826)
			(end -0.79248 0.4826)
			(stroke
				(width 0.1524)
				(type default)
			)
			(layer "F.SilkS")
		)
		(fp_line
			(start 1.16078 -0.4826)
			(end 1.16078 0.4826)
			(stroke
				(width 0.1524)
				(type default)
			)
			(layer "F.SilkS")
		)
		(fp_line
			(start 1.16078 0.4826)
			(end -0.64008 0.4826)
			(stroke
				(width 0.1524)
				(type default)
			)
			(layer "F.SilkS")
		)
		(fp_line
			(start -0.499872 -0.249936)
			(end 0.499872 -0.249936)
			(stroke
				(width 0.1)
				(type default)
			)
			(layer "F.Fab")
		)
		(fp_line
			(start -0.499872 0.249936)
			(end -0.499872 -0.249936)
			(stroke
				(width 0.1)
				(type default)
			)
			(layer "F.Fab")
		)
		(fp_line
			(start 0.499872 -0.249936)
			(end 0.499872 0.249936)
			(stroke
				(width 0.1)
				(type default)
			)
			(layer "F.Fab")
		)
		(fp_line
			(start 0.499872 0.249936)
			(end -0.499872 0.249936)
			(stroke
				(width 0.1)
				(type default)
			)
			(layer "F.Fab")
		)
		(pad "A" smd rect
			(at -0.47498 0)
			(size 0.6096 0.7112)
			(layers "F.Cu" "F.Mask" "F.Paste")
			(net "LED_FM_PCH_SLP_S4_N")
		)
		(pad "C" smd rect
			(at 0.47498 0)
			(size 0.6096 0.7112)
			(layers "F.Cu" "F.Mask" "F.Paste")
			(net "LED_FM_PCH_SLP_S4_N_D")
		)
	)
	(footprint ""
		(layer "F.Cu")
		(at 31.540196 -169.04081)
		(property "Reference" "PC394"
			(at 0 0 0)
			(layer "F.SilkS")
			(hide yes)
			(effects
				(font
					(size 1.27 1.27)
				)
			)
		)
		(property "Value" ""
			(at 0 0 0)
			(layer "F.Fab")
			(effects
				(font
					(size 1.27 1.27)
				)
			)
		)
		(duplicate_pad_numbers_are_jumpers no)
		(fp_line
			(start -0.7874 -0.4064)
			(end 0.7874 -0.4064)
			(stroke
				(width 0.1524)
				(type default)
			)
			(layer "F.SilkS")
		)
		(fp_line
			(start -0.7874 0.4064)
			(end -0.7874 -0.4064)
			(stroke
				(width 0.1524)
				(type default)
			)
			(layer "F.SilkS")
		)
		(fp_line
			(start 0.7874 -0.4064)
			(end 0.7874 0.4064)
			(stroke
				(width 0.1524)
				(type default)
			)
			(layer "F.SilkS")
		)
		(fp_line
			(start 0.7874 0.4064)
			(end -0.7874 0.4064)
			(stroke
				(width 0.1524)
				(type default)
			)
			(layer "F.SilkS")
		)
		(fp_line
			(start -0.67945 -0.305054)
			(end -0.12065 -0.305054)
			(stroke
				(width 0.1)
				(type default)
			)
			(layer "F.Fab")
		)
		(fp_line
			(start -0.67945 0.3048)
			(end -0.67945 -0.305054)
			(stroke
				(width 0.1)
				(type default)
			)
			(layer "F.Fab")
		)
		(fp_line
			(start -0.12065 -0.305054)
			(end -0.12065 -0.2794)
			(stroke
				(width 0.1)
				(type default)
			)
			(layer "F.Fab")
		)
		(fp_line
			(start -0.12065 -0.2794)
			(end 0.12065 -0.2794)
			(stroke
				(width 0.1)
				(type default)
			)
			(layer "F.Fab")
		)
		(fp_line
			(start -0.12065 0.2794)
			(end -0.12065 0.3048)
			(stroke
				(width 0.1)
				(type default)
			)
			(layer "F.Fab")
		)
		(fp_line
			(start -0.12065 0.3048)
			(end -0.67945 0.3048)
			(stroke
				(width 0.1)
				(type default)
			)
			(layer "F.Fab")
		)
		(fp_line
			(start 0.120396 0.2794)
			(end -0.12065 0.2794)
			(stroke
				(width 0.1)
				(type default)
			)
			(layer "F.Fab")
		)
		(fp_line
			(start 0.120396 0.3048)
			(end 0.120396 0.2794)
			(stroke
				(width 0.1)
				(type default)
			)
			(layer "F.Fab")
		)
		(fp_line
			(start 0.12065 -0.3048)
			(end 0.67945 -0.3048)
			(stroke
				(width 0.1)
				(type default)
			)
			(layer "F.Fab")
		)
		(fp_line
			(start 0.12065 -0.2794)
			(end 0.12065 -0.3048)
			(stroke
				(width 0.1)
				(type default)
			)
			(layer "F.Fab")
		)
		(fp_line
			(start 0.67945 -0.3048)
			(end 0.67945 0.3048)
			(stroke
				(width 0.1)
				(type default)
			)
			(layer "F.Fab")
		)
		(fp_line
			(start 0.67945 0.3048)
			(end 0.120396 0.3048)
			(stroke
				(width 0.1)
				(type default)
			)
			(layer "F.Fab")
		)
		(pad "1" smd circle
			(at -0.40005 0)
			(size 0 0)
			(layers "F.Cu" "F.Mask" "F.Paste")
			(net "PVCCD_HV_CPU1_VCC")
		)
		(pad "2" smd circle
			(at 0.40005 0)
			(size 0 0)
			(layers "F.Cu" "F.Mask" "F.Paste")
			(net "GND")
		)
	)
)
